(kicad_pcb
	(version 20260206)
	(generator "pcbnew")
	(generator_version "10.0")
	(general
		(thickness 1.6)
		(legacy_teardrops no)
	)
	(paper "A4")
	(title_block
		(title "baseboard — 13948-1b.1110WZS1818.brd")
		(comment 1 "Honey Badger (Wiwynn) / footprints 1291-1297 of 2523")
	)
	(layers
		(0 "F.Cu" signal "TOP")
		(4 "In1.Cu" signal "L2GND")
		(6 "In2.Cu" signal "L3")
		(8 "In3.Cu" signal "L4VCC")
		(10 "In4.Cu" signal "L5VCC")
		(12 "In5.Cu" signal "L6")
		(14 "In6.Cu" signal "L7GND")
		(2 "B.Cu" signal "BOTTOM")
		(9 "F.Adhes" user "F.Adhesive")
		(11 "B.Adhes" user "B.Adhesive")
		(13 "F.Paste" user "Package Geometry/Pastemask Top")
		(15 "B.Paste" user "Package Geometry/Pastemask Bottom")
		(5 "F.SilkS" user "Ref Des/Silkscreen Top")
		(7 "B.SilkS" user "Ref Des/Silkscreen Bottom")
		(1 "F.Mask" user "Board Geometry/Soldermask Top")
		(3 "B.Mask" user "Board Geometry/Soldermask Bottom")
		(17 "Dwgs.User" user "User.Drawings")
		(19 "Cmts.User" user "User.Comments")
		(21 "Eco1.User" user "User.Eco1")
		(23 "Eco2.User" user "User.Eco2")
		(25 "Edge.Cuts" user "Board Geometry/Outline")
		(27 "Margin" user)
		(31 "F.CrtYd" user "Package Geometry/Place Bound Top")
		(29 "B.CrtYd" user "Package Geometry/Place Bound Bottom")
		(35 "F.Fab" user "Ref Des/Assembly Top")
		(33 "B.Fab" user "Ref Des/Assembly Bottom")
	)
	(footprint ""
		(layer "F.Cu")
		(at 347.374718 -143.233648)
		(property "Reference" "C254"
			(at 0 0 0)
			(layer "F.SilkS")
			(hide yes)
			(effects
				(font
					(size 1.27 1.27)
				)
			)
		)
		(property "Value" "SC1U10V2KX-4-GP"
			(at 1.1811 -2.7051 0)
			(unlocked yes)
			(layer "F.Fab")
			(hide yes)
			(effects
				(font
					(size 1.016 1.016)
					(thickness 0.1524)
				)
			)
		)
		(property "Device Type" "C402H22"
			(at 1.1811 -4.2291 0)
			(unlocked yes)
			(layer "F.Fab")
			(hide yes)
			(effects
				(font
					(size 1.016 1.016)
					(thickness 0.1524)
				)
			)
		)
		(duplicate_pad_numbers_are_jumpers no)
		(fp_rect
			(start -0.4318 0.9525)
			(end 0.4318 -0.9525)
			(stroke
				(width 0)
				(type default)
			)
			(fill no)
			(layer "F.CrtYd")
		)
		(fp_rect
			(start -0.4318 0.9525)
			(end 0.4318 -0.9525)
			(stroke
				(width 0)
				(type default)
			)
			(fill no)
			(layer "F.Fab")
		)
		(pad "1" smd custom
			(at 0 -0.4445)
			(size 0.1524 0.1524)
			(layers "F.Cu" "F.Mask" "F.Paste")
			(net "P3V3_STBY")
			(options
				(clearance outline)
				(anchor circle)
			)
			(primitives
				(gr_poly
					(pts
						(arc
							(start 0.3048 -0.2032)
							(mid 0.275042 -0.275042)
							(end 0.2032 -0.3048)
						)
						(arc
							(start -0.2032 -0.3048)
							(mid -0.275042 -0.275042)
							(end -0.3048 -0.2032)
						)
						(arc
							(start -0.3048 0.2032)
							(mid -0.275042 0.275042)
							(end -0.2032 0.3048)
						)
						(arc
							(start 0.2032 0.3048)
							(mid 0.275042 0.275042)
							(end 0.3048 0.2032)
						)
					)
					(width 0)
					(fill yes)
				)
			)
		)
		(pad "2" smd custom
			(at 0 0.4445)
			(size 0.1524 0.1524)
			(layers "F.Cu" "F.Mask" "F.Paste")
			(net "GND")
			(options
				(clearance outline)
				(anchor circle)
			)
			(primitives
				(gr_poly
					(pts
						(arc
							(start 0.3048 -0.2032)
							(mid 0.275042 -0.275042)
							(end 0.2032 -0.3048)
						)
						(arc
							(start -0.2032 -0.3048)
							(mid -0.275042 -0.275042)
							(end -0.3048 -0.2032)
						)
						(arc
							(start -0.3048 0.2032)
							(mid -0.275042 0.275042)
							(end -0.2032 0.3048)
						)
						(arc
							(start 0.2032 0.3048)
							(mid 0.275042 0.275042)
							(end 0.3048 0.2032)
						)
					)
					(width 0)
					(fill yes)
				)
			)
		)
	)
	(footprint ""
		(layer "F.Cu")
		(at 332.431136 -200.033128)
		(property "Reference" "R198"
			(at 0 0 0)
			(layer "F.SilkS")
			(hide yes)
			(effects
				(font
					(size 1.27 1.27)
				)
			)
		)
		(property "Value" "8K2R2J-3-GP"
			(at 0.064008 -3.993896 0)
			(unlocked yes)
			(layer "F.Fab")
			(hide yes)
			(effects
				(font
					(size 1.016 1.016)
					(thickness 0.1524)
				)
			)
		)
		(property "Device Type" "R402H16"
			(at 0.064008 -5.517896 0)
			(unlocked yes)
			(layer "F.Fab")
			(hide yes)
			(effects
				(font
					(size 1.016 1.016)
					(thickness 0.1524)
				)
			)
		)
		(duplicate_pad_numbers_are_jumpers no)
		(fp_line
			(start -0.508 -0.9398)
			(end -0.508 0.9398)
			(stroke
				(width 0.1524)
				(type default)
			)
			(layer "F.SilkS")
		)
		(fp_line
			(start 0.508 -0.9398)
			(end -0.508 -0.9398)
			(stroke
				(width 0.1524)
				(type default)
			)
			(layer "F.SilkS")
		)
		(fp_rect
			(start -0.508 0.9398)
			(end 0.508 -0.9398)
			(stroke
				(width 0)
				(type default)
			)
			(fill no)
			(layer "F.CrtYd")
		)
		(fp_rect
			(start -0.508 0.9398)
			(end 0.508 -0.9398)
			(stroke
				(width 0)
				(type default)
			)
			(fill no)
			(layer "F.Fab")
		)
		(pad "1" smd custom
			(at 0 -0.4445)
			(size 0.1397 0.1397)
			(layers "F.Cu" "F.Mask" "F.Paste")
			(net "EEPROM_A1_R")
			(options
				(clearance outline)
				(anchor circle)
			)
			(primitives
				(gr_poly
					(pts
						(arc
							(start -0.1778 -0.2794)
							(mid -0.249642 -0.249642)
							(end -0.2794 -0.1778)
						)
						(arc
							(start -0.2794 0.1778)
							(mid -0.249642 0.249642)
							(end -0.1778 0.2794)
						)
						(arc
							(start 0.1778 0.2794)
							(mid 0.249642 0.249642)
							(end 0.2794 0.1778)
						)
						(arc
							(start 0.2794 -0.1778)
							(mid 0.249642 -0.249642)
							(end 0.1778 -0.2794)
						)
					)
					(width 0)
					(fill yes)
				)
			)
		)
		(pad "2" smd custom
			(at 0 0.4445)
			(size 0.1397 0.1397)
			(layers "F.Cu" "F.Mask" "F.Paste")
			(net "GND")
			(options
				(clearance outline)
				(anchor circle)
			)
			(primitives
				(gr_poly
					(pts
						(arc
							(start -0.1778 -0.2794)
							(mid -0.249642 -0.249642)
							(end -0.2794 -0.1778)
						)
						(arc
							(start -0.2794 0.1778)
							(mid -0.249642 0.249642)
							(end -0.1778 0.2794)
						)
						(arc
							(start 0.1778 0.2794)
							(mid 0.249642 0.249642)
							(end 0.2794 0.1778)
						)
						(arc
							(start 0.2794 -0.1778)
							(mid 0.249642 -0.249642)
							(end 0.1778 -0.2794)
						)
					)
					(width 0)
					(fill yes)
				)
			)
		)
	)
	(footprint ""
		(layer "F.Cu")
		(at 282.194 -188.976)
		(property "Reference" "R298"
			(at 0 0 0)
			(layer "F.SilkS")
			(hide yes)
			(effects
				(font
					(size 1.27 1.27)
				)
			)
		)
		(property "Value" "10R2F-L-GP"
			(at 0.064008 -3.993896 0)
			(unlocked yes)
			(layer "F.Fab")
			(hide yes)
			(effects
				(font
					(size 1.016 1.016)
					(thickness 0.1524)
				)
			)
		)
		(property "Device Type" "R402H14"
			(at 0.064008 -5.517896 0)
			(unlocked yes)
			(layer "F.Fab")
			(hide yes)
			(effects
				(font
					(size 1.016 1.016)
					(thickness 0.1524)
				)
			)
		)
		(duplicate_pad_numbers_are_jumpers no)
		(fp_line
			(start -0.508 -0.9398)
			(end -0.508 0.9398)
			(stroke
				(width 0.1524)
				(type default)
			)
			(layer "F.SilkS")
		)
		(fp_line
			(start 0.508 -0.9398)
			(end -0.508 -0.9398)
			(stroke
				(width 0.1524)
				(type default)
			)
			(layer "F.SilkS")
		)
		(fp_rect
			(start -0.508 0.9398)
			(end 0.508 -0.9398)
			(stroke
				(width 0)
				(type default)
			)
			(fill no)
			(layer "F.CrtYd")
		)
		(fp_rect
			(start -0.508 0.9398)
			(end 0.508 -0.9398)
			(stroke
				(width 0)
				(type default)
			)
			(fill no)
			(layer "F.Fab")
		)
		(pad "1" smd custom
			(at 0 -0.4445)
			(size 0.1397 0.1397)
			(layers "F.Cu" "F.Mask" "F.Paste")
			(net "OSC2_OUT")
			(options
				(clearance outline)
				(anchor circle)
			)
			(primitives
				(gr_poly
					(pts
						(arc
							(start -0.1778 -0.2794)
							(mid -0.249642 -0.249642)
							(end -0.2794 -0.1778)
						)
						(arc
							(start -0.2794 0.1778)
							(mid -0.249642 0.249642)
							(end -0.1778 0.2794)
						)
						(arc
							(start 0.1778 0.2794)
							(mid 0.249642 0.249642)
							(end 0.2794 0.1778)
						)
						(arc
							(start 0.2794 -0.1778)
							(mid 0.249642 -0.249642)
							(end 0.1778 -0.2794)
						)
					)
					(width 0)
					(fill yes)
				)
			)
		)
		(pad "2" smd custom
			(at 0 0.4445)
			(size 0.1397 0.1397)
			(layers "F.Cu" "F.Mask" "F.Paste")
			(net "OSC0_AS_CLKIN")
			(options
				(clearance outline)
				(anchor circle)
			)
			(primitives
				(gr_poly
					(pts
						(arc
							(start -0.1778 -0.2794)
							(mid -0.249642 -0.249642)
							(end -0.2794 -0.1778)
						)
						(arc
							(start -0.2794 0.1778)
							(mid -0.249642 0.249642)
							(end -0.1778 0.2794)
						)
						(arc
							(start 0.1778 0.2794)
							(mid 0.249642 0.249642)
							(end 0.2794 0.1778)
						)
						(arc
							(start 0.2794 -0.1778)
							(mid 0.249642 -0.249642)
							(end 0.1778 -0.2794)
						)
					)
					(width 0)
					(fill yes)
				)
			)
		)
	)
	(footprint ""
		(layer "F.Cu")
		(at 76.5556 -18.3896 180)
		(property "Reference" "PC208"
			(at 0 0 180)
			(layer "F.SilkS")
			(hide yes)
			(effects
				(font
					(size 1.27 1.27)
				)
			)
		)
		(property "Value" "SC1U25V3KX-GP"
			(at 0 -2.8194 180)
			(unlocked yes)
			(layer "F.Fab")
			(hide yes)
			(effects
				(font
					(size 1.016 1.016)
					(thickness 0.1524)
				)
			)
		)
		(property "Device Type" "C603H36"
			(at 0 -4.3434 180)
			(unlocked yes)
			(layer "F.Fab")
			(hide yes)
			(effects
				(font
					(size 1.016 1.016)
					(thickness 0.1524)
				)
			)
		)
		(duplicate_pad_numbers_are_jumpers no)
		(fp_line
			(start 0.508 0)
			(end -0.508 0)
			(stroke
				(width 0.2032)
				(type default)
			)
			(layer "F.SilkS")
		)
		(fp_rect
			(start -0.5842 1.3335)
			(end 0.5842 -1.3335)
			(stroke
				(width 0)
				(type default)
			)
			(fill no)
			(layer "F.CrtYd")
		)
		(fp_rect
			(start -0.5842 1.3335)
			(end 0.5842 -1.3335)
			(stroke
				(width 0)
				(type default)
			)
			(fill no)
			(layer "F.Fab")
		)
		(pad "1" smd custom
			(at 0 -0.762 180)
			(size 0.2159 0.2159)
			(layers "F.Cu" "F.Mask" "F.Paste")
			(net "VT235_VDDH")
			(options
				(clearance outline)
				(anchor circle)
			)
			(primitives
				(gr_poly
					(pts
						(arc
							(start -0.3302 -0.4318)
							(mid -0.402042 -0.402042)
							(end -0.4318 -0.3302)
						)
						(arc
							(start -0.4318 0.3302)
							(mid -0.402042 0.402042)
							(end -0.3302 0.4318)
						)
						(arc
							(start 0.3302 0.4318)
							(mid 0.402042 0.402042)
							(end 0.4318 0.3302)
						)
						(arc
							(start 0.4318 -0.3302)
							(mid 0.402042 -0.402042)
							(end 0.3302 -0.4318)
						)
					)
					(width 0)
					(fill yes)
				)
			)
		)
		(pad "2" smd custom
			(at 0 0.762 180)
			(size 0.2159 0.2159)
			(layers "F.Cu" "F.Mask" "F.Paste")
			(net "GND")
			(options
				(clearance outline)
				(anchor circle)
			)
			(primitives
				(gr_poly
					(pts
						(arc
							(start -0.3302 -0.4318)
							(mid -0.402042 -0.402042)
							(end -0.4318 -0.3302)
						)
						(arc
							(start -0.4318 0.3302)
							(mid -0.402042 0.402042)
							(end -0.3302 0.4318)
						)
						(arc
							(start 0.3302 0.4318)
							(mid 0.402042 0.402042)
							(end 0.4318 0.3302)
						)
						(arc
							(start 0.4318 -0.3302)
							(mid 0.402042 -0.402042)
							(end 0.3302 -0.4318)
						)
					)
					(width 0)
					(fill yes)
				)
			)
		)
	)
	(footprint ""
		(layer "F.Cu")
		(at 322.961 -138.938)
		(property "Reference" "R5202"
			(at 0 0 0)
			(layer "F.SilkS")
			(hide yes)
			(effects
				(font
					(size 1.27 1.27)
				)
			)
		)
		(property "Value" "1KR2J-1-GP"
			(at 0.064008 -3.993896 0)
			(unlocked yes)
			(layer "F.Fab")
			(hide yes)
			(effects
				(font
					(size 1.016 1.016)
					(thickness 0.1524)
				)
			)
		)
		(property "Device Type" "R402H16"
			(at 0.064008 -5.517896 0)
			(unlocked yes)
			(layer "F.Fab")
			(hide yes)
			(effects
				(font
					(size 1.016 1.016)
					(thickness 0.1524)
				)
			)
		)
		(duplicate_pad_numbers_are_jumpers no)
		(fp_line
			(start -0.508 -0.9398)
			(end -0.508 0.9398)
			(stroke
				(width 0.1524)
				(type default)
			)
			(layer "F.SilkS")
		)
		(fp_line
			(start 0.508 -0.9398)
			(end -0.508 -0.9398)
			(stroke
				(width 0.1524)
				(type default)
			)
			(layer "F.SilkS")
		)
		(fp_rect
			(start -0.508 0.9398)
			(end 0.508 -0.9398)
			(stroke
				(width 0)
				(type default)
			)
			(fill no)
			(layer "F.CrtYd")
		)
		(fp_rect
			(start -0.508 0.9398)
			(end 0.508 -0.9398)
			(stroke
				(width 0)
				(type default)
			)
			(fill no)
			(layer "F.Fab")
		)
		(pad "1" smd custom
			(at 0 -0.4445)
			(size 0.1397 0.1397)
			(layers "F.Cu" "F.Mask" "F.Paste")
			(net "P3V0_BAT_R")
			(options
				(clearance outline)
				(anchor circle)
			)
			(primitives
				(gr_poly
					(pts
						(arc
							(start -0.1778 -0.2794)
							(mid -0.249642 -0.249642)
							(end -0.2794 -0.1778)
						)
						(arc
							(start -0.2794 0.1778)
							(mid -0.249642 0.249642)
							(end -0.1778 0.2794)
						)
						(arc
							(start 0.1778 0.2794)
							(mid 0.249642 0.249642)
							(end 0.2794 0.1778)
						)
						(arc
							(start 0.2794 -0.1778)
							(mid 0.249642 -0.249642)
							(end 0.1778 -0.2794)
						)
					)
					(width 0)
					(fill yes)
				)
			)
		)
		(pad "2" smd custom
			(at 0 0.4445)
			(size 0.1397 0.1397)
			(layers "F.Cu" "F.Mask" "F.Paste")
			(net "P3V0_BAT")
			(options
				(clearance outline)
				(anchor circle)
			)
			(primitives
				(gr_poly
					(pts
						(arc
							(start -0.1778 -0.2794)
							(mid -0.249642 -0.249642)
							(end -0.2794 -0.1778)
						)
						(arc
							(start -0.2794 0.1778)
							(mid -0.249642 0.249642)
							(end -0.1778 0.2794)
						)
						(arc
							(start 0.1778 0.2794)
							(mid 0.249642 0.249642)
							(end 0.2794 0.1778)
						)
						(arc
							(start 0.2794 -0.1778)
							(mid 0.249642 -0.249642)
							(end 0.1778 -0.2794)
						)
					)
					(width 0)
					(fill yes)
				)
			)
		)
	)
	(footprint ""
		(layer "F.Cu")
		(at 6.427216 -226.62388 180)
		(property "Reference" "R158"
			(at 0 0 180)
			(layer "F.SilkS")
			(hide yes)
			(effects
				(font
					(size 1.27 1.27)
				)
			)
		)
		(property "Value" "0R2J-2-GP"
			(at 0.064008 -3.993896 180)
			(unlocked yes)
			(layer "F.Fab")
			(hide yes)
			(effects
				(font
					(size 1.016 1.016)
					(thickness 0.1524)
				)
			)
		)
		(property "Device Type" "R402H16"
			(at 0.064008 -5.517896 180)
			(unlocked yes)
			(layer "F.Fab")
			(hide yes)
			(effects
				(font
					(size 1.016 1.016)
					(thickness 0.1524)
				)
			)
		)
		(duplicate_pad_numbers_are_jumpers no)
		(fp_line
			(start 0.508 -0.9398)
			(end -0.508 -0.9398)
			(stroke
				(width 0.1524)
				(type default)
			)
			(layer "F.SilkS")
		)
		(fp_line
			(start -0.508 -0.9398)
			(end -0.508 0.9398)
			(stroke
				(width 0.1524)
				(type default)
			)
			(layer "F.SilkS")
		)
		(fp_rect
			(start -0.508 0.9398)
			(end 0.508 -0.9398)
			(stroke
				(width 0)
				(type default)
			)
			(fill no)
			(layer "F.CrtYd")
		)
		(fp_rect
			(start -0.508 0.9398)
			(end 0.508 -0.9398)
			(stroke
				(width 0)
				(type default)
			)
			(fill no)
			(layer "F.Fab")
		)
		(pad "1" smd custom
			(at 0 -0.4445 180)
			(size 0.1397 0.1397)
			(layers "F.Cu" "F.Mask" "F.Paste")
			(net "SAS_SEB_PEER_PRSNT_BMC")
			(options
				(clearance outline)
				(anchor circle)
			)
			(primitives
				(gr_poly
					(pts
						(arc
							(start -0.1778 -0.2794)
							(mid -0.249642 -0.249642)
							(end -0.2794 -0.1778)
						)
						(arc
							(start -0.2794 0.1778)
							(mid -0.249642 0.249642)
							(end -0.1778 0.2794)
						)
						(arc
							(start 0.1778 0.2794)
							(mid 0.249642 0.249642)
							(end 0.2794 0.1778)
						)
						(arc
							(start 0.2794 -0.1778)
							(mid 0.249642 -0.249642)
							(end 0.1778 -0.2794)
						)
					)
					(width 0)
					(fill yes)
				)
			)
		)
		(pad "2" smd custom
			(at 0 0.4445 180)
			(size 0.1397 0.1397)
			(layers "F.Cu" "F.Mask" "F.Paste")
			(net "SAS_SEB_PEER_PRSNT")
			(options
				(clearance outline)
				(anchor circle)
			)
			(primitives
				(gr_poly
					(pts
						(arc
							(start -0.1778 -0.2794)
							(mid -0.249642 -0.249642)
							(end -0.2794 -0.1778)
						)
						(arc
							(start -0.2794 0.1778)
							(mid -0.249642 0.249642)
							(end -0.1778 0.2794)
						)
						(arc
							(start 0.1778 0.2794)
							(mid 0.249642 0.249642)
							(end 0.2794 0.1778)
						)
						(arc
							(start 0.2794 -0.1778)
							(mid 0.249642 -0.249642)
							(end 0.1778 -0.2794)
						)
					)
					(width 0)
					(fill yes)
				)
			)
		)
	)
	(footprint ""
		(layer "F.Cu")
		(at 231.267 -17.907 -90)
		(property "Reference" "R529"
			(at 0 0 270)
			(layer "F.SilkS")
			(hide yes)
			(effects
				(font
					(size 1.27 1.27)
				)
			)
		)
		(property "Value" "1KR2F-3-GP"
			(at 0.064008 -3.993896 270)
			(unlocked yes)
			(layer "F.Fab")
			(hide yes)
			(effects
				(font
					(size 1.016 1.016)
					(thickness 0.1524)
				)
			)
		)
		(property "Device Type" "R402H16"
			(at 0.064008 -5.517896 270)
			(unlocked yes)
			(layer "F.Fab")
			(hide yes)
			(effects
				(font
					(size 1.016 1.016)
					(thickness 0.1524)
				)
			)
		)
		(duplicate_pad_numbers_are_jumpers no)
		(fp_line
			(start -0.508 -0.9398)
			(end -0.508 0.9398)
			(stroke
				(width 0.1524)
				(type default)
			)
			(layer "F.SilkS")
		)
		(fp_line
			(start 0.508 -0.9398)
			(end -0.508 -0.9398)
			(stroke
				(width 0.1524)
				(type default)
			)
			(layer "F.SilkS")
		)
		(fp_rect
			(start -0.508 0.9398)
			(end 0.508 -0.9398)
			(stroke
				(width 0)
				(type default)
			)
			(fill no)
			(layer "F.CrtYd")
		)
		(fp_rect
			(start -0.508 0.9398)
			(end 0.508 -0.9398)
			(stroke
				(width 0)
				(type default)
			)
			(fill no)
			(layer "F.Fab")
		)
		(pad "1" smd custom
			(at 0 -0.4445 270)
			(size 0.1397 0.1397)
			(layers "F.Cu" "F.Mask" "F.Paste")
			(net "ENCLO_LED_RED_G")
			(options
				(clearance outline)
				(anchor circle)
			)
			(primitives
				(gr_poly
					(pts
						(arc
							(start -0.1778 -0.2794)
							(mid -0.249642 -0.249642)
							(end -0.2794 -0.1778)
						)
						(arc
							(start -0.2794 0.1778)
							(mid -0.249642 0.249642)
							(end -0.1778 0.2794)
						)
						(arc
							(start 0.1778 0.2794)
							(mid 0.249642 0.249642)
							(end 0.2794 0.1778)
						)
						(arc
							(start 0.2794 -0.1778)
							(mid 0.249642 -0.249642)
							(end 0.1778 -0.2794)
						)
					)
					(width 0)
					(fill yes)
				)
			)
		)
		(pad "2" smd custom
			(at 0 0.4445 270)
			(size 0.1397 0.1397)
			(layers "F.Cu" "F.Mask" "F.Paste")
			(net "GND")
			(options
				(clearance outline)
				(anchor circle)
			)
			(primitives
				(gr_poly
					(pts
						(arc
							(start -0.1778 -0.2794)
							(mid -0.249642 -0.249642)
							(end -0.2794 -0.1778)
						)
						(arc
							(start -0.2794 0.1778)
							(mid -0.249642 0.249642)
							(end -0.1778 0.2794)
						)
						(arc
							(start 0.1778 0.2794)
							(mid 0.249642 0.249642)
							(end 0.2794 0.1778)
						)
						(arc
							(start 0.2794 -0.1778)
							(mid 0.249642 -0.249642)
							(end 0.1778 -0.2794)
						)
					)
					(width 0)
					(fill yes)
				)
			)
		)
	)
)
